# T6G (Grand Teton) — schematic netlist excerpt (pin names and nets, part order shuffled) for the footprints in the layout excerpt that follows; sources: Cadence DE-HDL packaged netlist, KiCad conversion of 04192023_DAF0TMB3IC0_F0TG_MB_C_brd_V02_OCP.brd

PC115_6  Q_CAP  1UF 25V 10% X6S  pkg C0402  page 203 : A = SW_P12V_AUX_PVDDCR_CPU1_P0_FLT ; B = GND
R1173  Q_RES  33.2 1% CHIP  pkg 0402LF  page 142 : A = OCP_V3_2_P3V3_R3_PWRGD ; B = HP_LVC3_OCP_V3_2_PWRGD
D1  BAT547F  IC  pkg SOT23_123XB  page 188 : \1\ = P3V3 ; \3\ = P5V

(kicad_pcb
	(version 20260206)
	(generator "pcbnew")
	(generator_version "10.0")
	(general
		(thickness 1.6)
		(legacy_teardrops no)
	)
	(paper "A4")
	(title_block
		(title "04192023_DAF0TMB3IC0_F0TG_MB_C_brd_V02_OCP.brd")
		(comment 1 "Grand Teton / footprints 4675-4677 of 8354")
	)
	(layers
		(0 "F.Cu" signal "TOP")
		(4 "In1.Cu" signal "GND")
		(6 "In2.Cu" signal "IN1")
		(8 "In3.Cu" signal "GND1")
		(10 "In4.Cu" signal "IN2")
		(12 "In5.Cu" signal "GND2")
		(14 "In6.Cu" signal "IN3")
		(16 "In7.Cu" signal "GND3")
		(18 "In8.Cu" signal "VCC")
		(20 "In9.Cu" signal "VCC1")
		(22 "In10.Cu" signal "GND4")
		(24 "In11.Cu" signal "IN4")
		(26 "In12.Cu" signal "GND5")
		(28 "In13.Cu" signal "IN5")
		(30 "In14.Cu" signal "GND6")
		(32 "In15.Cu" signal "IN6")
		(34 "In16.Cu" signal "GND7")
		(2 "B.Cu" signal "BOTTOM")
		(9 "F.Adhes" user "F.Adhesive")
		(11 "B.Adhes" user "B.Adhesive")
		(13 "F.Paste" user "Package Geometry/Pastemask Top")
		(15 "B.Paste" user "Package Geometry/Pastemask Bottom")
		(5 "F.SilkS" user "Ref Des/Silkscreen Top")
		(7 "B.SilkS" user "Ref Des/Silkscreen Bottom")
		(1 "F.Mask" user "Board Geometry/Soldermask Top")
		(3 "B.Mask" user "Board Geometry/Soldermask Bottom")
		(17 "Dwgs.User" user "User.Drawings")
		(19 "Cmts.User" user "User.Comments")
		(21 "Eco1.User" user "User.Eco1")
		(23 "Eco2.User" user "User.Eco2")
		(25 "Edge.Cuts" user "Board Geometry/Outline")
		(27 "Margin" user)
		(31 "F.CrtYd" user "Package Geometry/Place Bound Top")
		(29 "B.CrtYd" user "Package Geometry/Place Bound Bottom")
		(35 "F.Fab" user "Ref Des/Assembly Top")
		(33 "B.Fab" user "Ref Des/Assembly Bottom")
	)
	(footprint ""
		(layer "F.Cu")
		(at 355.300534 -340.084664 -90)
		(property "Reference" "PC115_6"
			(at 0 0 270)
			(layer "F.SilkS")
			(hide yes)
			(effects
				(font
					(size 1.27 1.27)
				)
			)
		)
		(property "Value" ""
			(at 0 0 270)
			(layer "F.Fab")
			(effects
				(font
					(size 1.27 1.27)
				)
			)
		)
		(duplicate_pad_numbers_are_jumpers no)
		(fp_line
			(start -0.7874 0.4064)
			(end -0.7874 -0.4064)
			(stroke
				(width 0.1524)
				(type default)
			)
			(layer "F.SilkS")
		)
		(fp_line
			(start 0.7874 0.4064)
			(end -0.7874 0.4064)
			(stroke
				(width 0.1524)
				(type default)
			)
			(layer "F.SilkS")
		)
		(fp_line
			(start -0.7874 -0.4064)
			(end 0.7874 -0.4064)
			(stroke
				(width 0.1524)
				(type default)
			)
			(layer "F.SilkS")
		)
		(fp_line
			(start 0.7874 -0.4064)
			(end 0.7874 0.4064)
			(stroke
				(width 0.1524)
				(type default)
			)
			(layer "F.SilkS")
		)
		(fp_line
			(start -0.67945 0.3048)
			(end -0.67945 -0.305054)
			(stroke
				(width 0.1)
				(type default)
			)
			(layer "F.Fab")
		)
		(fp_line
			(start -0.12065 0.3048)
			(end -0.67945 0.3048)
			(stroke
				(width 0.1)
				(type default)
			)
			(layer "F.Fab")
		)
		(fp_line
			(start 0.120396 0.3048)
			(end 0.120396 0.2794)
			(stroke
				(width 0.1)
				(type default)
			)
			(layer "F.Fab")
		)
		(fp_line
			(start 0.67945 0.3048)
			(end 0.120396 0.3048)
			(stroke
				(width 0.1)
				(type default)
			)
			(layer "F.Fab")
		)
		(fp_line
			(start -0.12065 0.2794)
			(end -0.12065 0.3048)
			(stroke
				(width 0.1)
				(type default)
			)
			(layer "F.Fab")
		)
		(fp_line
			(start 0.120396 0.2794)
			(end -0.12065 0.2794)
			(stroke
				(width 0.1)
				(type default)
			)
			(layer "F.Fab")
		)
		(fp_line
			(start -0.12065 -0.2794)
			(end 0.12065 -0.2794)
			(stroke
				(width 0.1)
				(type default)
			)
			(layer "F.Fab")
		)
		(fp_line
			(start 0.12065 -0.2794)
			(end 0.12065 -0.3048)
			(stroke
				(width 0.1)
				(type default)
			)
			(layer "F.Fab")
		)
		(fp_line
			(start 0.12065 -0.3048)
			(end 0.67945 -0.3048)
			(stroke
				(width 0.1)
				(type default)
			)
			(layer "F.Fab")
		)
		(fp_line
			(start 0.67945 -0.3048)
			(end 0.67945 0.3048)
			(stroke
				(width 0.1)
				(type default)
			)
			(layer "F.Fab")
		)
		(fp_line
			(start -0.67945 -0.305054)
			(end -0.12065 -0.305054)
			(stroke
				(width 0.1)
				(type default)
			)
			(layer "F.Fab")
		)
		(fp_line
			(start -0.12065 -0.305054)
			(end -0.12065 -0.2794)
			(stroke
				(width 0.1)
				(type default)
			)
			(layer "F.Fab")
		)
		(pad "1" smd circle
			(at -0.40005 0 270)
			(size 0 0)
			(layers "F.Cu" "F.Mask" "F.Paste")
			(net "SW_P12V_AUX_PVDDCR_CPU1_P0_FLT")
		)
		(pad "2" smd circle
			(at 0.40005 0 270)
			(size 0 0)
			(layers "F.Cu" "F.Mask" "F.Paste")
			(net "GND")
		)
	)
	(footprint ""
		(layer "F.Cu")
		(at 73.393046 -62.969394 -90)
		(property "Reference" "R1173"
			(at 0 0 270)
			(layer "F.SilkS")
			(hide yes)
			(effects
				(font
					(size 1.27 1.27)
				)
			)
		)
		(property "Value" ""
			(at 0 0 270)
			(layer "F.Fab")
			(effects
				(font
					(size 1.27 1.27)
				)
			)
		)
		(duplicate_pad_numbers_are_jumpers no)
		(fp_line
			(start -0.7874 0.4064)
			(end -0.7874 -0.4064)
			(stroke
				(width 0.1524)
				(type default)
			)
			(layer "F.SilkS")
		)
		(fp_line
			(start 0.7874 0.4064)
			(end -0.7874 0.4064)
			(stroke
				(width 0.1524)
				(type default)
			)
			(layer "F.SilkS")
		)
		(fp_line
			(start -0.7874 -0.4064)
			(end 0.7874 -0.4064)
			(stroke
				(width 0.1524)
				(type default)
			)
			(layer "F.SilkS")
		)
		(fp_line
			(start 0.7874 -0.4064)
			(end 0.7874 0.4064)
			(stroke
				(width 0.1524)
				(type default)
			)
			(layer "F.SilkS")
		)
		(fp_line
			(start -0.67945 0.3048)
			(end -0.67945 -0.305054)
			(stroke
				(width 0.1)
				(type default)
			)
			(layer "F.Fab")
		)
		(fp_line
			(start -0.12065 0.3048)
			(end -0.67945 0.3048)
			(stroke
				(width 0.1)
				(type default)
			)
			(layer "F.Fab")
		)
		(fp_line
			(start 0.120396 0.3048)
			(end 0.120396 0.2794)
			(stroke
				(width 0.1)
				(type default)
			)
			(layer "F.Fab")
		)
		(fp_line
			(start 0.67945 0.3048)
			(end 0.120396 0.3048)
			(stroke
				(width 0.1)
				(type default)
			)
			(layer "F.Fab")
		)
		(fp_line
			(start -0.12065 0.2794)
			(end -0.12065 0.3048)
			(stroke
				(width 0.1)
				(type default)
			)
			(layer "F.Fab")
		)
		(fp_line
			(start 0.120396 0.2794)
			(end -0.12065 0.2794)
			(stroke
				(width 0.1)
				(type default)
			)
			(layer "F.Fab")
		)
		(fp_line
			(start -0.12065 -0.2794)
			(end 0.12065 -0.2794)
			(stroke
				(width 0.1)
				(type default)
			)
			(layer "F.Fab")
		)
		(fp_line
			(start 0.12065 -0.2794)
			(end 0.12065 -0.3048)
			(stroke
				(width 0.1)
				(type default)
			)
			(layer "F.Fab")
		)
		(fp_line
			(start 0.12065 -0.3048)
			(end 0.67945 -0.3048)
			(stroke
				(width 0.1)
				(type default)
			)
			(layer "F.Fab")
		)
		(fp_line
			(start 0.67945 -0.3048)
			(end 0.67945 0.3048)
			(stroke
				(width 0.1)
				(type default)
			)
			(layer "F.Fab")
		)
		(fp_line
			(start -0.67945 -0.305054)
			(end -0.12065 -0.305054)
			(stroke
				(width 0.1)
				(type default)
			)
			(layer "F.Fab")
		)
		(fp_line
			(start -0.12065 -0.305054)
			(end -0.12065 -0.2794)
			(stroke
				(width 0.1)
				(type default)
			)
			(layer "F.Fab")
		)
		(pad "1" smd circle
			(at -0.40005 0 270)
			(size 0 0)
			(layers "F.Cu" "F.Mask" "F.Paste")
			(net "OCP_V3_2_P3V3_R3_PWRGD")
		)
		(pad "2" smd circle
			(at 0.40005 0 270)
			(size 0 0)
			(layers "F.Cu" "F.Mask" "F.Paste")
			(net "HP_LVC3_OCP_V3_2_PWRGD")
		)
	)
	(footprint ""
		(layer "F.Cu")
		(at 424.579288 -53.388514 180)
		(property "Reference" "D1"
			(at -1.418844 -2.46126 0)
			(unlocked yes)
			(layer "F.SilkS")
			(effects
				(font
					(size 0.7874 0.5842)
					(thickness 0.1524)
				)
				(justify left)
			)
		)
		(property "Value" ""
			(at 0 0 180)
			(layer "F.Fab")
			(effects
				(font
					(size 1.27 1.27)
				)
			)
		)
		(duplicate_pad_numbers_are_jumpers no)
		(fp_line
			(start 1.584198 1.500124)
			(end 1.584198 -1.500124)
			(stroke
				(width 0.1524)
				(type default)
			)
			(layer "F.SilkS")
		)
		(fp_line
			(start 1.584198 -1.500124)
			(end -1.584198 -1.500124)
			(stroke
				(width 0.1524)
				(type default)
			)
			(layer "F.SilkS")
		)
		(fp_line
			(start -1.584198 1.500124)
			(end 1.584198 1.500124)
			(stroke
				(width 0.1524)
				(type default)
			)
			(layer "F.SilkS")
		)
		(fp_line
			(start -1.584198 -1.500124)
			(end -1.584198 1.500124)
			(stroke
				(width 0.1524)
				(type default)
			)
			(layer "F.SilkS")
		)
		(fp_line
			(start 0.700024 1.500124)
			(end 0.700024 -1.500124)
			(stroke
				(width 0.1)
				(type default)
			)
			(layer "F.Fab")
		)
		(fp_line
			(start 0.700024 -1.500124)
			(end -0.700024 -1.500124)
			(stroke
				(width 0.1)
				(type default)
			)
			(layer "F.Fab")
		)
		(fp_line
			(start -0.700024 1.500124)
			(end 0.700024 1.500124)
			(stroke
				(width 0.1)
				(type default)
			)
			(layer "F.Fab")
		)
		(fp_line
			(start -0.700024 -1.500124)
			(end -0.700024 1.500124)
			(stroke
				(width 0.1)
				(type default)
			)
			(layer "F.Fab")
		)
		(pad "1" smd rect
			(at -0.999998 -0.94996 90)
			(size 0.8128 0.9144)
			(layers "F.Cu" "F.Mask" "F.Paste")
			(net "P3V3")
		)
		(pad "2" smd rect
			(at -0.999998 0.94996 90)
			(size 0.8128 0.9144)
			(layers "F.Cu" "F.Mask" "F.Paste")
			(net "Net_10752")
		)
		(pad "3" smd rect
			(at 0.999998 0 90)
			(size 0.8128 0.9144)
			(layers "F.Cu" "F.Mask" "F.Paste")
			(net "P5V")
		)
	)
)
